(kicad_pcb
	(version 20260206)
	(generator "pcbnew")
	(generator_version "10.0")
	(general
		(thickness 1.6)
		(legacy_teardrops no)
	)
	(paper "A4")
	(title_block
		(title "pdpb — Lightning_PDPB_BRD.brd")
		(comment 1 "Lightning (Wiwynn / Facebook NVMe JBOF) / footprints 144-147 of 1140")
	)
	(layers
		(0 "F.Cu" signal "TOP")
		(4 "In1.Cu" signal "L2GND")
		(6 "In2.Cu" signal "L3")
		(8 "In3.Cu" signal "L4VCC")
		(10 "In4.Cu" signal "L5VCC")
		(12 "In5.Cu" signal "L6")
		(14 "In6.Cu" signal "L7GND")
		(2 "B.Cu" signal "BOTTOM")
		(9 "F.Adhes" user "F.Adhesive")
		(11 "B.Adhes" user "B.Adhesive")
		(13 "F.Paste" user "Package Geometry/Pastemask Top")
		(15 "B.Paste" user "Package Geometry/Pastemask Bottom")
		(5 "F.SilkS" user "Ref Des/Silkscreen Top")
		(7 "B.SilkS" user "Ref Des/Silkscreen Bottom")
		(1 "F.Mask" user "Board Geometry/Soldermask Top")
		(3 "B.Mask" user "Board Geometry/Soldermask Bottom")
		(17 "Dwgs.User" user "User.Drawings")
		(19 "Cmts.User" user "User.Comments")
		(21 "Eco1.User" user "User.Eco1")
		(23 "Eco2.User" user "User.Eco2")
		(25 "Edge.Cuts" user "Board Geometry/Outline")
		(27 "Margin" user)
		(31 "F.CrtYd" user "Package Geometry/Place Bound Top")
		(29 "B.CrtYd" user "Package Geometry/Place Bound Bottom")
		(35 "F.Fab" user "Ref Des/Assembly Top")
		(33 "B.Fab" user "Ref Des/Assembly Bottom")
	)
	(footprint ""
		(layer "F.Cu")
		(at 101.346 -213.487 -90)
		(property "Reference" "R9509"
			(at 0 0 270)
			(layer "F.SilkS")
			(hide yes)
			(effects
				(font
					(size 1.27 1.27)
				)
			)
		)
		(property "Value" "4K7R2F-GP"
			(at 0.064008 -3.993896 270)
			(unlocked yes)
			(layer "F.Fab")
			(hide yes)
			(effects
				(font
					(size 1.016 1.016)
					(thickness 0.1524)
				)
			)
		)
		(property "Device Type" "R402H16"
			(at 0.064008 -5.517896 270)
			(unlocked yes)
			(layer "F.Fab")
			(hide yes)
			(effects
				(font
					(size 1.016 1.016)
					(thickness 0.1524)
				)
			)
		)
		(duplicate_pad_numbers_are_jumpers no)
		(fp_line
			(start -0.508 -0.9398)
			(end -0.508 0.9398)
			(stroke
				(width 0.1524)
				(type default)
			)
			(layer "F.SilkS")
		)
		(fp_line
			(start 0.508 -0.9398)
			(end -0.508 -0.9398)
			(stroke
				(width 0.1524)
				(type default)
			)
			(layer "F.SilkS")
		)
		(fp_rect
			(start -0.508 0.9398)
			(end 0.508 -0.9398)
			(stroke
				(width 0)
				(type default)
			)
			(fill no)
			(layer "F.CrtYd")
		)
		(fp_rect
			(start -0.508 0.9398)
			(end 0.508 -0.9398)
			(stroke
				(width 0)
				(type default)
			)
			(fill no)
			(layer "F.Fab")
		)
		(pad "1" smd custom
			(at 0 -0.4445 270)
			(size 0.1397 0.1397)
			(layers "F.Cu" "F.Mask" "F.Paste")
			(net "P3V3")
			(options
				(clearance outline)
				(anchor circle)
			)
			(primitives
				(gr_poly
					(pts
						(arc
							(start -0.1778 -0.2794)
							(mid -0.249642 -0.249642)
							(end -0.2794 -0.1778)
						)
						(arc
							(start -0.2794 0.1778)
							(mid -0.249642 0.249642)
							(end -0.1778 0.2794)
						)
						(arc
							(start 0.1778 0.2794)
							(mid 0.249642 0.249642)
							(end 0.2794 0.1778)
						)
						(arc
							(start 0.2794 -0.1778)
							(mid 0.249642 -0.249642)
							(end 0.1778 -0.2794)
						)
					)
					(width 0)
					(fill yes)
				)
			)
		)
		(pad "2" smd custom
			(at 0 0.4445 270)
			(size 0.1397 0.1397)
			(layers "F.Cu" "F.Mask" "F.Paste")
			(net "CLK_BUFFER_EU3_VOE_N")
			(options
				(clearance outline)
				(anchor circle)
			)
			(primitives
				(gr_poly
					(pts
						(arc
							(start -0.1778 -0.2794)
							(mid -0.249642 -0.249642)
							(end -0.2794 -0.1778)
						)
						(arc
							(start -0.2794 0.1778)
							(mid -0.249642 0.249642)
							(end -0.1778 0.2794)
						)
						(arc
							(start 0.1778 0.2794)
							(mid 0.249642 0.249642)
							(end 0.2794 0.1778)
						)
						(arc
							(start 0.2794 -0.1778)
							(mid 0.249642 -0.249642)
							(end 0.1778 -0.2794)
						)
					)
					(width 0)
					(fill yes)
				)
			)
		)
	)
	(footprint ""
		(layer "F.Cu")
		(at 21.8694 -467.5124 90)
		(property "Reference" "R9848"
			(at 0 0 90)
			(layer "F.SilkS")
			(hide yes)
			(effects
				(font
					(size 1.27 1.27)
				)
			)
		)
		(property "Value" "0R2J-2-GP"
			(at 0.064008 -3.993896 90)
			(unlocked yes)
			(layer "F.Fab")
			(hide yes)
			(effects
				(font
					(size 1.016 1.016)
					(thickness 0.1524)
				)
			)
		)
		(property "Device Type" "R402H16"
			(at 0.064008 -5.517896 90)
			(unlocked yes)
			(layer "F.Fab")
			(hide yes)
			(effects
				(font
					(size 1.016 1.016)
					(thickness 0.1524)
				)
			)
		)
		(duplicate_pad_numbers_are_jumpers no)
		(fp_line
			(start 0.508 -0.9398)
			(end -0.508 -0.9398)
			(stroke
				(width 0.1524)
				(type default)
			)
			(layer "F.SilkS")
		)
		(fp_line
			(start -0.508 -0.9398)
			(end -0.508 0.9398)
			(stroke
				(width 0.1524)
				(type default)
			)
			(layer "F.SilkS")
		)
		(fp_rect
			(start -0.508 0.9398)
			(end 0.508 -0.9398)
			(stroke
				(width 0)
				(type default)
			)
			(fill no)
			(layer "F.CrtYd")
		)
		(fp_rect
			(start -0.508 0.9398)
			(end 0.508 -0.9398)
			(stroke
				(width 0)
				(type default)
			)
			(fill no)
			(layer "F.Fab")
		)
		(pad "1" smd custom
			(at 0 -0.4445 90)
			(size 0.1397 0.1397)
			(layers "F.Cu" "F.Mask" "F.Paste")
			(net "ATTN_LED_DR10_R")
			(options
				(clearance outline)
				(anchor circle)
			)
			(primitives
				(gr_poly
					(pts
						(arc
							(start -0.1778 -0.2794)
							(mid -0.249642 -0.249642)
							(end -0.2794 -0.1778)
						)
						(arc
							(start -0.2794 0.1778)
							(mid -0.249642 0.249642)
							(end -0.1778 0.2794)
						)
						(arc
							(start 0.1778 0.2794)
							(mid 0.249642 0.249642)
							(end 0.2794 0.1778)
						)
						(arc
							(start 0.2794 -0.1778)
							(mid 0.249642 -0.249642)
							(end 0.1778 -0.2794)
						)
					)
					(width 0)
					(fill yes)
				)
			)
		)
		(pad "2" smd custom
			(at 0 0.4445 90)
			(size 0.1397 0.1397)
			(layers "F.Cu" "F.Mask" "F.Paste")
			(net "ATTN_LED_DR10_N")
			(options
				(clearance outline)
				(anchor circle)
			)
			(primitives
				(gr_poly
					(pts
						(arc
							(start -0.1778 -0.2794)
							(mid -0.249642 -0.249642)
							(end -0.2794 -0.1778)
						)
						(arc
							(start -0.2794 0.1778)
							(mid -0.249642 0.249642)
							(end -0.1778 0.2794)
						)
						(arc
							(start 0.1778 0.2794)
							(mid 0.249642 0.249642)
							(end 0.2794 0.1778)
						)
						(arc
							(start 0.2794 -0.1778)
							(mid 0.249642 -0.249642)
							(end 0.1778 -0.2794)
						)
					)
					(width 0)
					(fill yes)
				)
			)
		)
	)
	(footprint ""
		(layer "F.Cu")
		(at 228.346 -93.6244)
		(property "Reference" "R9244"
			(at 0 0 0)
			(layer "F.SilkS")
			(hide yes)
			(effects
				(font
					(size 1.27 1.27)
				)
			)
		)
		(property "Value" "2R2010F-GP"
			(at 0.0762 -4.5466 0)
			(unlocked yes)
			(layer "F.Fab")
			(hide yes)
			(effects
				(font
					(size 1.016 1.016)
					(thickness 0.1524)
				)
			)
		)
		(property "Device Type" "R2010H26"
			(at 0.0762 -6.1468 0)
			(unlocked yes)
			(layer "F.Fab")
			(hide yes)
			(effects
				(font
					(size 1.016 1.016)
					(thickness 0.1524)
				)
			)
		)
		(duplicate_pad_numbers_are_jumpers no)
		(fp_line
			(start -3.302 -1.651)
			(end -3.302 1.651)
			(stroke
				(width 0.1524)
				(type default)
			)
			(layer "F.SilkS")
		)
		(fp_line
			(start -3.302 1.651)
			(end 3.302 1.651)
			(stroke
				(width 0.1524)
				(type default)
			)
			(layer "F.SilkS")
		)
		(fp_line
			(start 3.302 -1.651)
			(end -3.302 -1.651)
			(stroke
				(width 0.1524)
				(type default)
			)
			(layer "F.SilkS")
		)
		(fp_line
			(start 3.302 1.651)
			(end 3.302 -1.651)
			(stroke
				(width 0.1524)
				(type default)
			)
			(layer "F.SilkS")
		)
		(fp_rect
			(start -3.3782 1.7272)
			(end 3.3782 -1.7272)
			(stroke
				(width 0)
				(type default)
			)
			(fill no)
			(layer "F.CrtYd")
		)
		(fp_poly
			(pts
				(xy 3.3782 -1.7272) (xy -3.3782 -1.7272) (xy -3.3782 1.7272) (xy 3.3782 1.7272)
			)
			(stroke
				(width 0)
				(type default)
			)
			(fill no)
			(layer "F.Fab")
		)
		(pad "1" smd rect
			(at -2.3495 0)
			(size 1.143 2.794)
			(layers "F.Cu" "F.Mask" "F.Paste")
			(net "P12V_SSD4")
		)
		(pad "2" smd rect
			(at 2.3495 0)
			(size 1.143 2.794)
			(layers "F.Cu" "F.Mask" "F.Paste")
			(net "12V_PRECH_SSD4")
		)
	)
	(footprint ""
		(layer "F.Cu")
		(at 23.998174 -62.083442 -90)
		(property "Reference" "U211"
			(at 0 0 270)
			(layer "F.SilkS")
			(hide yes)
			(effects
				(font
					(size 1.27 1.27)
				)
			)
		)
		(property "Value" "SN74LVC1G08DCKR-GP"
			(at -2.3368 -8.6868 270)
			(unlocked yes)
			(layer "F.Fab")
			(hide yes)
			(effects
				(font
					(size 1.016 1.016)
					(thickness 0.1524)
				)
			)
		)
		(property "Device Type" "SC70-5H44"
			(at -2.3114 -10.414 270)
			(unlocked yes)
			(layer "F.Fab")
			(hide yes)
			(effects
				(font
					(size 1.016 1.016)
					(thickness 0.1524)
				)
			)
		)
		(duplicate_pad_numbers_are_jumpers no)
		(fp_line
			(start -1.27 1.7018)
			(end -1.27 -1.7018)
			(stroke
				(width 0.1524)
				(type default)
			)
			(layer "F.SilkS")
		)
		(fp_line
			(start 1.27 1.7018)
			(end -1.27 1.7018)
			(stroke
				(width 0.1524)
				(type default)
			)
			(layer "F.SilkS")
		)
		(fp_line
			(start -1.27 -1.7018)
			(end 1.27 -1.7018)
			(stroke
				(width 0.1524)
				(type default)
			)
			(layer "F.SilkS")
		)
		(fp_line
			(start 1.27 -1.7018)
			(end 1.27 1.7018)
			(stroke
				(width 0.1524)
				(type default)
			)
			(layer "F.SilkS")
		)
		(fp_line
			(start 0.6604 -1.8034)
			(end 1.3843 -1.8034)
			(stroke
				(width 0.3302)
				(type default)
			)
			(layer "F.SilkS")
		)
		(fp_line
			(start 1.3843 -1.8034)
			(end 1.3843 -1.1176)
			(stroke
				(width 0.3302)
				(type default)
			)
			(layer "F.SilkS")
		)
		(fp_rect
			(start -1.524 1.9558)
			(end 1.524 -1.9558)
			(stroke
				(width 0)
				(type default)
			)
			(fill no)
			(layer "F.CrtYd")
		)
		(fp_poly
			(pts
				(xy -1.524 -1.9558) (xy 1.524 -1.9558) (xy 1.524 1.9558) (xy -1.524 1.9558)
			)
			(stroke
				(width 0)
				(type default)
			)
			(fill no)
			(layer "F.Fab")
		)
		(pad "1" smd rect
			(at 0.65024 -0.8255 270)
			(size 0.4064 1.2192)
			(layers "F.Cu" "F.Mask" "F.Paste")
			(net "SSD14_CLK0_OE_MOS_N")
		)
		(pad "2" smd rect
			(at 0 -0.8255 270)
			(size 0.4064 1.2192)
			(layers "F.Cu" "F.Mask" "F.Paste")
			(net "ATTN_LED_DR14_N")
		)
		(pad "3" smd rect
			(at -0.65024 -0.8255 270)
			(size 0.4064 1.2192)
			(layers "F.Cu" "F.Mask" "F.Paste")
			(net "GND")
		)
		(pad "4" smd rect
			(at -0.65024 0.8255 270)
			(size 0.4064 1.2192)
			(layers "F.Cu" "F.Mask" "F.Paste")
			(net "ATTN_LED_DR14_AND")
		)
		(pad "5" smd rect
			(at 0.65024 0.8255 270)
			(size 0.4064 1.2192)
			(layers "F.Cu" "F.Mask" "F.Paste")
			(net "P3V3")
		)
	)
)
